(kicad_pcb
	(version 20260206)
	(generator "pcbnew")
	(generator_version "10.0")
	(general
		(thickness 1.6)
		(legacy_teardrops no)
	)
	(paper "A4")
	(title_block
		(title "pdpb — Lightning_PDPB_BRD.brd")
		(comment 1 "Lightning (Wiwynn / Facebook NVMe JBOF) / footprints 92-92 of 1140")
	)
	(layers
		(0 "F.Cu" signal "TOP")
		(4 "In1.Cu" signal "L2GND")
		(6 "In2.Cu" signal "L3")
		(8 "In3.Cu" signal "L4VCC")
		(10 "In4.Cu" signal "L5VCC")
		(12 "In5.Cu" signal "L6")
		(14 "In6.Cu" signal "L7GND")
		(2 "B.Cu" signal "BOTTOM")
		(9 "F.Adhes" user "F.Adhesive")
		(11 "B.Adhes" user "B.Adhesive")
		(13 "F.Paste" user "Package Geometry/Pastemask Top")
		(15 "B.Paste" user "Package Geometry/Pastemask Bottom")
		(5 "F.SilkS" user "Ref Des/Silkscreen Top")
		(7 "B.SilkS" user "Ref Des/Silkscreen Bottom")
		(1 "F.Mask" user "Board Geometry/Soldermask Top")
		(3 "B.Mask" user "Board Geometry/Soldermask Bottom")
		(17 "Dwgs.User" user "User.Drawings")
		(19 "Cmts.User" user "User.Comments")
		(21 "Eco1.User" user "User.Eco1")
		(23 "Eco2.User" user "User.Eco2")
		(25 "Edge.Cuts" user "Board Geometry/Outline")
		(27 "Margin" user)
		(31 "F.CrtYd" user "Package Geometry/Place Bound Top")
		(29 "B.CrtYd" user "Package Geometry/Place Bound Bottom")
		(35 "F.Fab" user "Ref Des/Assembly Top")
		(33 "B.Fab" user "Ref Des/Assembly Bottom")
	)
	(footprint ""
		(layer "F.Cu")
		(at 24.003 -300.228)
		(property "Reference" "R9767"
			(at 0 0 0)
			(layer "F.SilkS")
			(hide yes)
			(effects
				(font
					(size 1.27 1.27)
				)
			)
		)
		(property "Value" "4K7R2J-2-GP"
			(at 0.064008 -3.993896 0)
			(unlocked yes)
			(layer "F.Fab")
			(hide yes)
			(effects
				(font
					(size 1.016 1.016)
					(thickness 0.1524)
				)
			)
		)
		(property "Device Type" "R402H16"
			(at 0.064008 -5.517896 0)
			(unlocked yes)
			(layer "F.Fab")
			(hide yes)
			(effects
				(font
					(size 1.016 1.016)
					(thickness 0.1524)
				)
			)
		)
		(duplicate_pad_numbers_are_jumpers no)
		(fp_line
			(start -0.508 -0.9398)
			(end -0.508 0.9398)
			(stroke
				(width 0.1524)
				(type default)
			)
			(layer "F.SilkS")
		)
		(fp_line
			(start 0.508 -0.9398)
			(end -0.508 -0.9398)
			(stroke
				(width 0.1524)
				(type default)
			)
			(layer "F.SilkS")
		)
		(fp_rect
			(start -0.508 0.9398)
			(end 0.508 -0.9398)
			(stroke
				(width 0)
				(type default)
			)
			(fill no)
			(layer "F.CrtYd")
		)
		(fp_rect
			(start -0.508 0.9398)
			(end 0.508 -0.9398)
			(stroke
				(width 0)
				(type default)
			)
			(fill no)
			(layer "F.Fab")
		)
		(pad "1" smd custom
			(at 0 -0.4445)
			(size 0.1397 0.1397)
			(layers "F.Cu" "F.Mask" "F.Paste")
			(net "SSD7_PWREN")
			(options
				(clearance outline)
				(anchor circle)
			)
			(primitives
				(gr_poly
					(pts
						(arc
							(start -0.1778 -0.2794)
							(mid -0.249642 -0.249642)
							(end -0.2794 -0.1778)
						)
						(arc
							(start -0.2794 0.1778)
							(mid -0.249642 0.249642)
							(end -0.1778 0.2794)
						)
						(arc
							(start 0.1778 0.2794)
							(mid 0.249642 0.249642)
							(end 0.2794 0.1778)
						)
						(arc
							(start 0.2794 -0.1778)
							(mid 0.249642 -0.249642)
							(end 0.1778 -0.2794)
						)
					)
					(width 0)
					(fill yes)
				)
			)
		)
		(pad "2" smd custom
			(at 0 0.4445)
			(size 0.1397 0.1397)
			(layers "F.Cu" "F.Mask" "F.Paste")
			(net "GND")
			(options
				(clearance outline)
				(anchor circle)
			)
			(primitives
				(gr_poly
					(pts
						(arc
							(start -0.1778 -0.2794)
							(mid -0.249642 -0.249642)
							(end -0.2794 -0.1778)
						)
						(arc
							(start -0.2794 0.1778)
							(mid -0.249642 0.249642)
							(end -0.1778 0.2794)
						)
						(arc
							(start 0.1778 0.2794)
							(mid 0.249642 0.249642)
							(end 0.2794 0.1778)
						)
						(arc
							(start 0.2794 -0.1778)
							(mid 0.249642 -0.249642)
							(end 0.1778 -0.2794)
						)
					)
					(width 0)
					(fill yes)
				)
			)
		)
	)
)
